(kicad_pcb
	(version 20260206)
	(generator "pcbnew")
	(generator_version "10.0")
	(general
		(thickness 1.6)
		(legacy_teardrops no)
	)
	(paper "A4")
	(title_block
		(title "Bryce Canyon_SCC_16316-1_OCP.brd")
		(comment 1 "Bryce Canyon / footprints 667-674 of 1561")
	)
	(layers
		(0 "F.Cu" signal "TOP")
		(4 "In1.Cu" signal "L2GND")
		(6 "In2.Cu" signal "L3")
		(8 "In3.Cu" signal "L4VCC")
		(10 "In4.Cu" signal "L5VCC")
		(12 "In5.Cu" signal "L6")
		(14 "In6.Cu" signal "L7GND")
		(2 "B.Cu" signal "BOTTOM")
		(9 "F.Adhes" user "F.Adhesive")
		(11 "B.Adhes" user "B.Adhesive")
		(13 "F.Paste" user "Package Geometry/Pastemask Top")
		(15 "B.Paste" user "Package Geometry/Pastemask Bottom")
		(5 "F.SilkS" user "Ref Des/Silkscreen Top")
		(7 "B.SilkS" user "Ref Des/Silkscreen Bottom")
		(1 "F.Mask" user "Board Geometry/Soldermask Top")
		(3 "B.Mask" user "Board Geometry/Soldermask Bottom")
		(17 "Dwgs.User" user "User.Drawings")
		(19 "Cmts.User" user "User.Comments")
		(21 "Eco1.User" user "User.Eco1")
		(23 "Eco2.User" user "User.Eco2")
		(25 "Edge.Cuts" user "Board Geometry/Outline")
		(27 "Margin" user)
		(31 "F.CrtYd" user "Package Geometry/Place Bound Top")
		(29 "B.CrtYd" user "Package Geometry/Place Bound Bottom")
		(35 "F.Fab" user "Ref Des/Assembly Top")
		(33 "B.Fab" user "Ref Des/Assembly Bottom")
	)
	(footprint ""
		(layer "F.Cu")
		(at 168.656 -14.097 180)
		(property "Reference" "R211"
			(at 0 0 180)
			(layer "F.SilkS")
			(hide yes)
			(effects
				(font
					(size 1.27 1.27)
				)
			)
		)
		(property "Value" "0R2J-2-GP"
			(at 0.064008 -3.993896 180)
			(unlocked yes)
			(layer "F.Fab")
			(hide yes)
			(effects
				(font
					(size 1.016 1.016)
					(thickness 0.1524)
				)
			)
		)
		(property "Device Type" "R402H16"
			(at 0.064008 -5.517896 180)
			(unlocked yes)
			(layer "F.Fab")
			(hide yes)
			(effects
				(font
					(size 1.016 1.016)
					(thickness 0.1524)
				)
			)
		)
		(duplicate_pad_numbers_are_jumpers no)
		(fp_line
			(start 0.508 -0.9398)
			(end -0.508 -0.9398)
			(stroke
				(width 0.1524)
				(type default)
			)
			(layer "F.SilkS")
		)
		(fp_line
			(start -0.508 -0.9398)
			(end -0.508 0.9398)
			(stroke
				(width 0.1524)
				(type default)
			)
			(layer "F.SilkS")
		)
		(fp_rect
			(start -0.508 0.9398)
			(end 0.508 -0.9398)
			(stroke
				(width 0)
				(type default)
			)
			(fill no)
			(layer "F.CrtYd")
		)
		(fp_rect
			(start -0.508 0.9398)
			(end 0.508 -0.9398)
			(stroke
				(width 0)
				(type default)
			)
			(fill no)
			(layer "F.Fab")
		)
		(pad "1" smd custom
			(at 0 -0.4445 180)
			(size 0.1397 0.1397)
			(layers "F.Cu" "F.Mask" "F.Paste")
			(net "P0V9_PG")
			(options
				(clearance outline)
				(anchor circle)
			)
			(primitives
				(gr_poly
					(pts
						(arc
							(start -0.1778 -0.2794)
							(mid -0.249642 -0.249642)
							(end -0.2794 -0.1778)
						)
						(arc
							(start -0.2794 0.1778)
							(mid -0.249642 0.249642)
							(end -0.1778 0.2794)
						)
						(arc
							(start 0.1778 0.2794)
							(mid 0.249642 0.249642)
							(end 0.2794 0.1778)
						)
						(arc
							(start 0.2794 -0.1778)
							(mid 0.249642 -0.249642)
							(end 0.1778 -0.2794)
						)
					)
					(width 0)
					(fill yes)
				)
			)
		)
		(pad "2" smd custom
			(at 0 0.4445 180)
			(size 0.1397 0.1397)
			(layers "F.Cu" "F.Mask" "F.Paste")
			(net "P0V9_PG_Q")
			(options
				(clearance outline)
				(anchor circle)
			)
			(primitives
				(gr_poly
					(pts
						(arc
							(start -0.1778 -0.2794)
							(mid -0.249642 -0.249642)
							(end -0.2794 -0.1778)
						)
						(arc
							(start -0.2794 0.1778)
							(mid -0.249642 0.249642)
							(end -0.1778 0.2794)
						)
						(arc
							(start 0.1778 0.2794)
							(mid 0.249642 0.249642)
							(end 0.2794 0.1778)
						)
						(arc
							(start 0.2794 -0.1778)
							(mid 0.249642 -0.249642)
							(end 0.1778 -0.2794)
						)
					)
					(width 0)
					(fill yes)
				)
			)
		)
	)
	(footprint ""
		(layer "F.Cu")
		(at 8.23087 -47.248318)
		(property "Reference" "R435"
			(at 0 0 0)
			(layer "F.SilkS")
			(hide yes)
			(effects
				(font
					(size 1.27 1.27)
				)
			)
		)
		(property "Value" "100R2D-GP"
			(at 0.064008 -3.993896 0)
			(unlocked yes)
			(layer "F.Fab")
			(hide yes)
			(effects
				(font
					(size 1.016 1.016)
					(thickness 0.1524)
				)
			)
		)
		(property "Device Type" "R402H14"
			(at 0.064008 -5.517896 0)
			(unlocked yes)
			(layer "F.Fab")
			(hide yes)
			(effects
				(font
					(size 1.016 1.016)
					(thickness 0.1524)
				)
			)
		)
		(duplicate_pad_numbers_are_jumpers no)
		(fp_line
			(start -0.508 -0.9398)
			(end -0.508 0.9398)
			(stroke
				(width 0.1524)
				(type default)
			)
			(layer "F.SilkS")
		)
		(fp_line
			(start 0.508 -0.9398)
			(end -0.508 -0.9398)
			(stroke
				(width 0.1524)
				(type default)
			)
			(layer "F.SilkS")
		)
		(fp_rect
			(start -0.508 0.9398)
			(end 0.508 -0.9398)
			(stroke
				(width 0)
				(type default)
			)
			(fill no)
			(layer "F.CrtYd")
		)
		(fp_rect
			(start -0.508 0.9398)
			(end 0.508 -0.9398)
			(stroke
				(width 0)
				(type default)
			)
			(fill no)
			(layer "F.Fab")
		)
		(pad "1" smd custom
			(at 0 -0.4445)
			(size 0.1397 0.1397)
			(layers "F.Cu" "F.Mask" "F.Paste")
			(net "GND")
			(options
				(clearance outline)
				(anchor circle)
			)
			(primitives
				(gr_poly
					(pts
						(arc
							(start -0.1778 -0.2794)
							(mid -0.249642 -0.249642)
							(end -0.2794 -0.1778)
						)
						(arc
							(start -0.2794 0.1778)
							(mid -0.249642 0.249642)
							(end -0.1778 0.2794)
						)
						(arc
							(start 0.1778 0.2794)
							(mid 0.249642 0.249642)
							(end 0.2794 0.1778)
						)
						(arc
							(start 0.2794 -0.1778)
							(mid 0.249642 -0.249642)
							(end 0.1778 -0.2794)
						)
					)
					(width 0)
					(fill yes)
				)
			)
		)
		(pad "2" smd custom
			(at 0 0.4445)
			(size 0.1397 0.1397)
			(layers "F.Cu" "F.Mask" "F.Paste")
			(net "MB0_TEMP_E")
			(options
				(clearance outline)
				(anchor circle)
			)
			(primitives
				(gr_poly
					(pts
						(arc
							(start -0.1778 -0.2794)
							(mid -0.249642 -0.249642)
							(end -0.2794 -0.1778)
						)
						(arc
							(start -0.2794 0.1778)
							(mid -0.249642 0.249642)
							(end -0.1778 0.2794)
						)
						(arc
							(start 0.1778 0.2794)
							(mid 0.249642 0.249642)
							(end 0.2794 0.1778)
						)
						(arc
							(start 0.2794 -0.1778)
							(mid 0.249642 -0.249642)
							(end 0.1778 -0.2794)
						)
					)
					(width 0)
					(fill yes)
				)
			)
		)
	)
	(footprint ""
		(layer "F.Cu")
		(at 189.73038 -78.49108)
		(property "Reference" "R364"
			(at 0 0 0)
			(layer "F.SilkS")
			(hide yes)
			(effects
				(font
					(size 1.27 1.27)
				)
			)
		)
		(property "Value" "4K7R2F-GP"
			(at 0.064008 -3.993896 0)
			(unlocked yes)
			(layer "F.Fab")
			(hide yes)
			(effects
				(font
					(size 1.016 1.016)
					(thickness 0.1524)
				)
			)
		)
		(property "Device Type" "R402H16"
			(at 0.064008 -5.517896 0)
			(unlocked yes)
			(layer "F.Fab")
			(hide yes)
			(effects
				(font
					(size 1.016 1.016)
					(thickness 0.1524)
				)
			)
		)
		(duplicate_pad_numbers_are_jumpers no)
		(fp_line
			(start -0.508 -0.9398)
			(end -0.508 0.9398)
			(stroke
				(width 0.1524)
				(type default)
			)
			(layer "F.SilkS")
		)
		(fp_line
			(start 0.508 -0.9398)
			(end -0.508 -0.9398)
			(stroke
				(width 0.1524)
				(type default)
			)
			(layer "F.SilkS")
		)
		(fp_rect
			(start -0.508 0.9398)
			(end 0.508 -0.9398)
			(stroke
				(width 0)
				(type default)
			)
			(fill no)
			(layer "F.CrtYd")
		)
		(fp_rect
			(start -0.508 0.9398)
			(end 0.508 -0.9398)
			(stroke
				(width 0)
				(type default)
			)
			(fill no)
			(layer "F.Fab")
		)
		(pad "1" smd custom
			(at 0 -0.4445)
			(size 0.1397 0.1397)
			(layers "F.Cu" "F.Mask" "F.Paste")
			(net "P3V3")
			(options
				(clearance outline)
				(anchor circle)
			)
			(primitives
				(gr_poly
					(pts
						(arc
							(start -0.1778 -0.2794)
							(mid -0.249642 -0.249642)
							(end -0.2794 -0.1778)
						)
						(arc
							(start -0.2794 0.1778)
							(mid -0.249642 0.249642)
							(end -0.1778 0.2794)
						)
						(arc
							(start 0.1778 0.2794)
							(mid 0.249642 0.249642)
							(end 0.2794 0.1778)
						)
						(arc
							(start 0.2794 -0.1778)
							(mid 0.249642 -0.249642)
							(end 0.1778 -0.2794)
						)
					)
					(width 0)
					(fill yes)
				)
			)
		)
		(pad "2" smd custom
			(at 0 0.4445)
			(size 0.1397 0.1397)
			(layers "F.Cu" "F.Mask" "F.Paste")
			(net "TEMP2_A1")
			(options
				(clearance outline)
				(anchor circle)
			)
			(primitives
				(gr_poly
					(pts
						(arc
							(start -0.1778 -0.2794)
							(mid -0.249642 -0.249642)
							(end -0.2794 -0.1778)
						)
						(arc
							(start -0.2794 0.1778)
							(mid -0.249642 0.249642)
							(end -0.1778 0.2794)
						)
						(arc
							(start 0.1778 0.2794)
							(mid 0.249642 0.249642)
							(end 0.2794 0.1778)
						)
						(arc
							(start 0.2794 -0.1778)
							(mid 0.249642 -0.249642)
							(end 0.1778 -0.2794)
						)
					)
					(width 0)
					(fill yes)
				)
			)
		)
	)
	(footprint ""
		(layer "F.Cu")
		(at 75.72629 -26.460958 -90)
		(property "Reference" "R348"
			(at 0 0 270)
			(layer "F.SilkS")
			(hide yes)
			(effects
				(font
					(size 1.27 1.27)
				)
			)
		)
		(property "Value" "0R2J-2-GP"
			(at 0.064008 -3.993896 270)
			(unlocked yes)
			(layer "F.Fab")
			(hide yes)
			(effects
				(font
					(size 1.016 1.016)
					(thickness 0.1524)
				)
			)
		)
		(property "Device Type" "R402H16"
			(at 0.064008 -5.517896 270)
			(unlocked yes)
			(layer "F.Fab")
			(hide yes)
			(effects
				(font
					(size 1.016 1.016)
					(thickness 0.1524)
				)
			)
		)
		(duplicate_pad_numbers_are_jumpers no)
		(fp_line
			(start -0.508 -0.9398)
			(end -0.508 0.9398)
			(stroke
				(width 0.1524)
				(type default)
			)
			(layer "F.SilkS")
		)
		(fp_line
			(start 0.508 -0.9398)
			(end -0.508 -0.9398)
			(stroke
				(width 0.1524)
				(type default)
			)
			(layer "F.SilkS")
		)
		(fp_rect
			(start -0.508 0.9398)
			(end 0.508 -0.9398)
			(stroke
				(width 0)
				(type default)
			)
			(fill no)
			(layer "F.CrtYd")
		)
		(fp_rect
			(start -0.508 0.9398)
			(end 0.508 -0.9398)
			(stroke
				(width 0)
				(type default)
			)
			(fill no)
			(layer "F.Fab")
		)
		(pad "1" smd custom
			(at 0 -0.4445 270)
			(size 0.1397 0.1397)
			(layers "F.Cu" "F.Mask" "F.Paste")
			(net "SCC_LOC_INS_N")
			(options
				(clearance outline)
				(anchor circle)
			)
			(primitives
				(gr_poly
					(pts
						(arc
							(start -0.1778 -0.2794)
							(mid -0.249642 -0.249642)
							(end -0.2794 -0.1778)
						)
						(arc
							(start -0.2794 0.1778)
							(mid -0.249642 0.249642)
							(end -0.1778 0.2794)
						)
						(arc
							(start 0.1778 0.2794)
							(mid 0.249642 0.249642)
							(end 0.2794 0.1778)
						)
						(arc
							(start 0.2794 -0.1778)
							(mid 0.249642 -0.249642)
							(end 0.1778 -0.2794)
						)
					)
					(width 0)
					(fill yes)
				)
			)
		)
		(pad "2" smd custom
			(at 0 0.4445 270)
			(size 0.1397 0.1397)
			(layers "F.Cu" "F.Mask" "F.Paste")
			(net "GND")
			(options
				(clearance outline)
				(anchor circle)
			)
			(primitives
				(gr_poly
					(pts
						(arc
							(start -0.1778 -0.2794)
							(mid -0.249642 -0.249642)
							(end -0.2794 -0.1778)
						)
						(arc
							(start -0.2794 0.1778)
							(mid -0.249642 0.249642)
							(end -0.1778 0.2794)
						)
						(arc
							(start 0.1778 0.2794)
							(mid 0.249642 0.249642)
							(end 0.2794 0.1778)
						)
						(arc
							(start 0.2794 -0.1778)
							(mid 0.249642 -0.249642)
							(end 0.1778 -0.2794)
						)
					)
					(width 0)
					(fill yes)
				)
			)
		)
	)
	(footprint ""
		(layer "F.Cu")
		(at 132.994908 -87.827866)
		(property "Reference" "TP18"
			(at 0 0 0)
			(layer "F.SilkS")
			(hide yes)
			(effects
				(font
					(size 1.27 1.27)
				)
			)
		)
		(property "Value" "TPAD28-2-GP"
			(at -0.0127 -1.6637 0)
			(unlocked yes)
			(layer "F.Fab")
			(hide yes)
			(effects
				(font
					(size 1.016 1.016)
					(thickness 0.1524)
				)
			)
		)
		(property "Device Type" "TPAD28"
			(at -0.0127 -3.1877 0)
			(unlocked yes)
			(layer "F.Fab")
			(hide yes)
			(effects
				(font
					(size 1.016 1.016)
					(thickness 0.1524)
				)
			)
		)
		(duplicate_pad_numbers_are_jumpers no)
		(fp_poly
			(pts
				(arc
					(start 0.3556 0)
					(mid -0.3556 0)
					(end 0.3556 0)
				)
			)
			(stroke
				(width 0)
				(type default)
			)
			(fill no)
			(layer "F.CrtYd")
		)
		(fp_poly
			(pts
				(arc
					(start 0.6096 0)
					(mid -0.6096 0)
					(end 0.6096 0)
				)
			)
			(stroke
				(width 0)
				(type default)
			)
			(fill no)
			(layer "F.Fab")
		)
		(pad "1" smd circle
			(at 0 0)
			(size 0.7112 0.7112)
			(layers "F.Cu" "F.Mask" "F.Paste")
			(net "EXP_I2C_SCL10")
		)
	)
	(footprint ""
		(layer "F.Cu")
		(at 150.5458 -121.6914 90)
		(property "Reference" "R373"
			(at 0 0 90)
			(layer "F.SilkS")
			(hide yes)
			(effects
				(font
					(size 1.27 1.27)
				)
			)
		)
		(property "Value" "10KR2F-2-GP"
			(at 0.064008 -3.993896 90)
			(unlocked yes)
			(layer "F.Fab")
			(hide yes)
			(effects
				(font
					(size 1.016 1.016)
					(thickness 0.1524)
				)
			)
		)
		(property "Device Type" "R402H16"
			(at 0.064008 -5.517896 90)
			(unlocked yes)
			(layer "F.Fab")
			(hide yes)
			(effects
				(font
					(size 1.016 1.016)
					(thickness 0.1524)
				)
			)
		)
		(duplicate_pad_numbers_are_jumpers no)
		(fp_line
			(start 0.508 -0.9398)
			(end -0.508 -0.9398)
			(stroke
				(width 0.1524)
				(type default)
			)
			(layer "F.SilkS")
		)
		(fp_line
			(start -0.508 -0.9398)
			(end -0.508 0.9398)
			(stroke
				(width 0.1524)
				(type default)
			)
			(layer "F.SilkS")
		)
		(fp_rect
			(start -0.508 0.9398)
			(end 0.508 -0.9398)
			(stroke
				(width 0)
				(type default)
			)
			(fill no)
			(layer "F.CrtYd")
		)
		(fp_rect
			(start -0.508 0.9398)
			(end 0.508 -0.9398)
			(stroke
				(width 0)
				(type default)
			)
			(fill no)
			(layer "F.Fab")
		)
		(pad "1" smd custom
			(at 0 -0.4445 90)
			(size 0.1397 0.1397)
			(layers "F.Cu" "F.Mask" "F.Paste")
			(net "P1V5_E_VFB")
			(options
				(clearance outline)
				(anchor circle)
			)
			(primitives
				(gr_poly
					(pts
						(arc
							(start -0.1778 -0.2794)
							(mid -0.249642 -0.249642)
							(end -0.2794 -0.1778)
						)
						(arc
							(start -0.2794 0.1778)
							(mid -0.249642 0.249642)
							(end -0.1778 0.2794)
						)
						(arc
							(start 0.1778 0.2794)
							(mid 0.249642 0.249642)
							(end 0.2794 0.1778)
						)
						(arc
							(start 0.2794 -0.1778)
							(mid 0.249642 -0.249642)
							(end 0.1778 -0.2794)
						)
					)
					(width 0)
					(fill yes)
				)
			)
		)
		(pad "2" smd custom
			(at 0 0.4445 90)
			(size 0.1397 0.1397)
			(layers "F.Cu" "F.Mask" "F.Paste")
			(net "AGND_P1V5_E")
			(options
				(clearance outline)
				(anchor circle)
			)
			(primitives
				(gr_poly
					(pts
						(arc
							(start -0.1778 -0.2794)
							(mid -0.249642 -0.249642)
							(end -0.2794 -0.1778)
						)
						(arc
							(start -0.2794 0.1778)
							(mid -0.249642 0.249642)
							(end -0.1778 0.2794)
						)
						(arc
							(start 0.1778 0.2794)
							(mid 0.249642 0.249642)
							(end 0.2794 0.1778)
						)
						(arc
							(start 0.2794 -0.1778)
							(mid 0.249642 -0.249642)
							(end 0.1778 -0.2794)
						)
					)
					(width 0)
					(fill yes)
				)
			)
		)
	)
	(footprint ""
		(layer "F.Cu")
		(at 83.999832 -111.675672 -90)
		(property "Reference" "C742"
			(at 0 0 270)
			(layer "F.SilkS")
			(hide yes)
			(effects
				(font
					(size 1.27 1.27)
				)
			)
		)
		(property "Value" "SCD1U16V2KX-3GP"
			(at 1.1811 -2.7051 270)
			(unlocked yes)
			(layer "F.Fab")
			(hide yes)
			(effects
				(font
					(size 1.016 1.016)
					(thickness 0.1524)
				)
			)
		)
		(property "Device Type" "C402H22"
			(at 1.1811 -4.2291 270)
			(unlocked yes)
			(layer "F.Fab")
			(hide yes)
			(effects
				(font
					(size 1.016 1.016)
					(thickness 0.1524)
				)
			)
		)
		(duplicate_pad_numbers_are_jumpers no)
		(fp_rect
			(start -0.4318 0.9525)
			(end 0.4318 -0.9525)
			(stroke
				(width 0)
				(type default)
			)
			(fill no)
			(layer "F.CrtYd")
		)
		(fp_rect
			(start -0.4318 0.9525)
			(end 0.4318 -0.9525)
			(stroke
				(width 0)
				(type default)
			)
			(fill no)
			(layer "F.Fab")
		)
		(pad "1" smd custom
			(at 0 -0.4445 270)
			(size 0.1524 0.1524)
			(layers "F.Cu" "F.Mask" "F.Paste")
			(net "U48_OE")
			(options
				(clearance outline)
				(anchor circle)
			)
			(primitives
				(gr_poly
					(pts
						(arc
							(start 0.3048 -0.2032)
							(mid 0.275042 -0.275042)
							(end 0.2032 -0.3048)
						)
						(arc
							(start -0.2032 -0.3048)
							(mid -0.275042 -0.275042)
							(end -0.3048 -0.2032)
						)
						(arc
							(start -0.3048 0.2032)
							(mid -0.275042 0.275042)
							(end -0.2032 0.3048)
						)
						(arc
							(start 0.2032 0.3048)
							(mid 0.275042 0.275042)
							(end 0.3048 0.2032)
						)
					)
					(width 0)
					(fill yes)
				)
			)
		)
		(pad "2" smd custom
			(at 0 0.4445 270)
			(size 0.1524 0.1524)
			(layers "F.Cu" "F.Mask" "F.Paste")
			(net "GND")
			(options
				(clearance outline)
				(anchor circle)
			)
			(primitives
				(gr_poly
					(pts
						(arc
							(start 0.3048 -0.2032)
							(mid 0.275042 -0.275042)
							(end 0.2032 -0.3048)
						)
						(arc
							(start -0.2032 -0.3048)
							(mid -0.275042 -0.275042)
							(end -0.3048 -0.2032)
						)
						(arc
							(start -0.3048 0.2032)
							(mid -0.275042 0.275042)
							(end -0.2032 0.3048)
						)
						(arc
							(start 0.2032 0.3048)
							(mid 0.275042 0.275042)
							(end 0.3048 0.2032)
						)
					)
					(width 0)
					(fill yes)
				)
			)
		)
	)
	(footprint ""
		(layer "F.Cu")
		(at 202.30338 -76.86548 -90)
		(property "Reference" "R367"
			(at 0 0 270)
			(layer "F.SilkS")
			(hide yes)
			(effects
				(font
					(size 1.27 1.27)
				)
			)
		)
		(property "Value" "0R2J-2-GP"
			(at 0.064008 -3.993896 270)
			(unlocked yes)
			(layer "F.Fab")
			(hide yes)
			(effects
				(font
					(size 1.016 1.016)
					(thickness 0.1524)
				)
			)
		)
		(property "Device Type" "R402H16"
			(at 0.064008 -5.517896 270)
			(unlocked yes)
			(layer "F.Fab")
			(hide yes)
			(effects
				(font
					(size 1.016 1.016)
					(thickness 0.1524)
				)
			)
		)
		(duplicate_pad_numbers_are_jumpers no)
		(fp_line
			(start -0.508 -0.9398)
			(end -0.508 0.9398)
			(stroke
				(width 0.1524)
				(type default)
			)
			(layer "F.SilkS")
		)
		(fp_line
			(start 0.508 -0.9398)
			(end -0.508 -0.9398)
			(stroke
				(width 0.1524)
				(type default)
			)
			(layer "F.SilkS")
		)
		(fp_rect
			(start -0.508 0.9398)
			(end 0.508 -0.9398)
			(stroke
				(width 0)
				(type default)
			)
			(fill no)
			(layer "F.CrtYd")
		)
		(fp_rect
			(start -0.508 0.9398)
			(end 0.508 -0.9398)
			(stroke
				(width 0)
				(type default)
			)
			(fill no)
			(layer "F.Fab")
		)
		(pad "1" smd custom
			(at 0 -0.4445 270)
			(size 0.1397 0.1397)
			(layers "F.Cu" "F.Mask" "F.Paste")
			(net "I2C_SCC_SDA2")
			(options
				(clearance outline)
				(anchor circle)
			)
			(primitives
				(gr_poly
					(pts
						(arc
							(start -0.1778 -0.2794)
							(mid -0.249642 -0.249642)
							(end -0.2794 -0.1778)
						)
						(arc
							(start -0.2794 0.1778)
							(mid -0.249642 0.249642)
							(end -0.1778 0.2794)
						)
						(arc
							(start 0.1778 0.2794)
							(mid 0.249642 0.249642)
							(end 0.2794 0.1778)
						)
						(arc
							(start 0.2794 -0.1778)
							(mid 0.249642 -0.249642)
							(end 0.1778 -0.2794)
						)
					)
					(width 0)
					(fill yes)
				)
			)
		)
		(pad "2" smd custom
			(at 0 0.4445 270)
			(size 0.1397 0.1397)
			(layers "F.Cu" "F.Mask" "F.Paste")
			(net "TEMP2_SDA")
			(options
				(clearance outline)
				(anchor circle)
			)
			(primitives
				(gr_poly
					(pts
						(arc
							(start -0.1778 -0.2794)
							(mid -0.249642 -0.249642)
							(end -0.2794 -0.1778)
						)
						(arc
							(start -0.2794 0.1778)
							(mid -0.249642 0.249642)
							(end -0.1778 0.2794)
						)
						(arc
							(start 0.1778 0.2794)
							(mid 0.249642 0.249642)
							(end 0.2794 0.1778)
						)
						(arc
							(start 0.2794 -0.1778)
							(mid 0.249642 -0.249642)
							(end 0.1778 -0.2794)
						)
					)
					(width 0)
					(fill yes)
				)
			)
		)
	)
)
